# BASEBOARD_FAB2 (Tioga Pass) — schematic netlist excerpt (pin names and nets, part order shuffled) for the footprints in the layout excerpt that follows; sources: Cadence DE-HDL packaged netlist, KiCad conversion of Wiwynn_Tioga_Pass_MB.brd

R2L20  RES  63.4K 1.0% CHIP  pkg 0402  page 237 : A = P1V8_PCH_STBY ; B = VR_P1V8_PCH_STBY_FB
R3M3  RES  22.1 1.0% CHIP  pkg 0402  page 218 : A = PWRGD_PVDDQ_DEF_R ; B = PWRGD_PVDDQ_DEF
C1G7  ST270U2D5VBM-GP  pkg SMD-TCG2  page 225 : \1\ = VR_FET_SW_P12V_STBY_PVDDQ_GHJ ; \2\ = GND

(kicad_pcb
	(version 20260206)
	(generator "pcbnew")
	(generator_version "10.0")
	(general
		(thickness 1.6)
		(legacy_teardrops no)
	)
	(paper "A4")
	(title_block
		(title "Wiwynn_Tioga_Pass_MB.brd")
		(comment 1 "Tioga Pass / footprints 3881-3883 of 4770")
	)
	(layers
		(0 "F.Cu" signal "TOP")
		(4 "In1.Cu" signal "L2GND")
		(6 "In2.Cu" signal "L3")
		(8 "In3.Cu" signal "L4GND")
		(10 "In4.Cu" signal "L5")
		(12 "In5.Cu" signal "L6GND")
		(14 "In6.Cu" signal "L7VCC")
		(16 "In7.Cu" signal "L8VCC")
		(18 "In8.Cu" signal "L9GND")
		(20 "In9.Cu" signal "L10")
		(22 "In10.Cu" signal "L11GND")
		(24 "In11.Cu" signal "L12")
		(26 "In12.Cu" signal "L13GND")
		(2 "B.Cu" signal "BOTTOM")
		(9 "F.Adhes" user "F.Adhesive")
		(11 "B.Adhes" user "B.Adhesive")
		(13 "F.Paste" user "Package Geometry/Pastemask Top")
		(15 "B.Paste" user "Package Geometry/Pastemask Bottom")
		(5 "F.SilkS" user "Ref Des/Silkscreen Top")
		(7 "B.SilkS" user "Ref Des/Silkscreen Bottom")
		(1 "F.Mask" user "Board Geometry/Soldermask Top")
		(3 "B.Mask" user "Board Geometry/Soldermask Bottom")
		(17 "Dwgs.User" user "User.Drawings")
		(19 "Cmts.User" user "User.Comments")
		(21 "Eco1.User" user "User.Eco1")
		(23 "Eco2.User" user "User.Eco2")
		(25 "Edge.Cuts" user "Board Geometry/Outline")
		(27 "Margin" user)
		(31 "F.CrtYd" user "Package Geometry/Place Bound Top")
		(29 "B.CrtYd" user "Package Geometry/Place Bound Bottom")
		(35 "F.Fab" user "Ref Des/Assembly Top")
		(33 "B.Fab" user "Ref Des/Assembly Bottom")
	)
	(footprint ""
		(layer "B.Cu")
		(at 404.3172 -148.082 -90)
		(property "Reference" "R2L20"
			(at 0 0 90)
			(layer "B.SilkS")
			(hide yes)
			(effects
				(font
					(size 1.27 1.27)
				)
				(justify mirror)
			)
		)
		(property "Value" ""
			(at 0 0 90)
			(layer "B.Fab")
			(effects
				(font
					(size 1.27 1.27)
				)
				(justify mirror)
			)
		)
		(duplicate_pad_numbers_are_jumpers no)
		(fp_poly
			(pts
				(xy 0.2794 -0.1016) (xy -0.2794 -0.1016) (xy -0.2794 0.9906) (xy 0.2794 0.9906)
			)
			(stroke
				(width 0)
				(type default)
			)
			(fill no)
			(layer "B.CrtYd")
		)
		(fp_line
			(start -0.2794 0.9906)
			(end -0.2794 -0.1016)
			(stroke
				(width 0.1)
				(type default)
			)
			(layer "B.Fab")
		)
		(fp_line
			(start 0.2794 0.9906)
			(end -0.2794 0.9906)
			(stroke
				(width 0.1)
				(type default)
			)
			(layer "B.Fab")
		)
		(fp_line
			(start -0.2794 -0.1016)
			(end 0.2794 -0.1016)
			(stroke
				(width 0.1)
				(type default)
			)
			(layer "B.Fab")
		)
		(fp_line
			(start 0.2794 -0.1016)
			(end 0.2794 0.9906)
			(stroke
				(width 0.1)
				(type default)
			)
			(layer "B.Fab")
		)
		(pad "1" smd rect
			(at 0 0 90)
			(size 0.508 0.508)
			(layers "B.Cu" "B.Mask" "B.Paste")
			(net "P1V8_PCH_STBY")
		)
		(pad "2" smd rect
			(at 0 0.889 90)
			(size 0.508 0.508)
			(layers "B.Cu" "B.Mask" "B.Paste")
			(net "VR_P1V8_PCH_STBY_FB")
		)
		(zone
			(layer "B.Cu")
			(hatch none 0.5)
			(connect_pads
				(clearance 0)
			)
			(min_thickness 0.25)
			(keepout
				(tracks not_allowed)
				(vias allowed)
				(pads allowed)
				(copperpour not_allowed)
				(footprints allowed)
			)
			(placement
				(enabled no)
				(sheetname "")
			)
			(fill
				(thermal_gap 0.5)
				(thermal_bridge_width 0.5)
				(island_removal_mode 0)
			)
			(polygon
				(pts
					(xy 403.6822 -147.828) (xy 403.6822 -148.336) (xy 404.0632 -148.336) (xy 404.0632 -147.828)
				)
			)
		)
		(zone
			(layer "B.Cu")
			(hatch none 0.5)
			(connect_pads
				(clearance 0)
			)
			(min_thickness 0.25)
			(keepout
				(tracks allowed)
				(vias not_allowed)
				(pads allowed)
				(copperpour not_allowed)
				(footprints allowed)
			)
			(placement
				(enabled no)
				(sheetname "")
			)
			(fill
				(thermal_gap 0.5)
				(thermal_bridge_width 0.5)
				(island_removal_mode 0)
			)
			(polygon
				(pts
					(xy 404.0632 -147.828) (xy 404.0632 -148.336) (xy 403.6822 -148.336) (xy 403.6822 -147.828)
				)
			)
		)
	)
	(footprint ""
		(layer "B.Cu")
		(at -2.59842 -18.11782 -90)
		(property "Reference" "C1G7"
			(at 0 0 90)
			(layer "B.SilkS")
			(hide yes)
			(effects
				(font
					(size 1.27 1.27)
				)
				(justify mirror)
			)
		)
		(property "Value" "*"
			(at 2.3114 0.10795 270)
			(unlocked yes)
			(layer "B.Fab")
			(hide yes)
			(effects
				(font
					(size 0.889 0.889)
					(thickness 0.1524)
				)
				(justify mirror)
			)
		)
		(property "Device Type" "ST270U2D5VBM-GP_SMD-TCG2-ST270A"
			(at 2.3114 -1.41605 270)
			(unlocked yes)
			(layer "B.Fab")
			(hide yes)
			(effects
				(font
					(size 0.889 0.889)
					(thickness 0.1524)
				)
				(justify mirror)
			)
		)
		(duplicate_pad_numbers_are_jumpers no)
		(fp_line
			(start 1.5494 0.4826)
			(end 1.5494 -0.4826)
			(stroke
				(width 0.1524)
				(type default)
			)
			(layer "B.SilkS")
		)
		(fp_line
			(start -1.5494 -0.4826)
			(end -1.5494 0.4826)
			(stroke
				(width 0.1524)
				(type default)
			)
			(layer "B.SilkS")
		)
		(fp_line
			(start 1.0922 -2.35458)
			(end -1.0922 -2.35458)
			(stroke
				(width 0.508)
				(type default)
			)
			(layer "B.SilkS")
		)
		(fp_poly
			(pts
				(xy 1.3462 1.9558) (xy 1.3462 1.905) (xy 1.5494 1.905) (xy 1.5494 -1.905) (xy 1.3462 -1.905) (xy 1.3462 -1.9558)
				(xy -1.3462 -1.9558) (xy -1.3462 -1.905) (xy -1.5494 -1.905) (xy -1.5494 1.905) (xy -1.3462 1.905)
				(xy -1.3462 1.9558)
			)
			(stroke
				(width 0)
				(type default)
			)
			(fill no)
			(layer "B.CrtYd")
		)
		(fp_poly
			(pts
				(xy 1.3462 1.9558) (xy 1.3462 1.905) (xy 1.5494 1.905) (xy 1.5494 -1.905) (xy 1.3462 -1.905) (xy 1.3462 -1.9558)
				(xy -1.3462 -1.9558) (xy -1.3462 -1.905) (xy -1.5494 -1.905) (xy -1.5494 1.905) (xy -1.3462 1.905)
				(xy -1.3462 1.9558)
			)
			(stroke
				(width 0)
				(type default)
			)
			(fill no)
			(layer "B.Fab")
		)
		(pad "1" smd rect
			(at 0 -1.27508 90)
			(size 2.6924 1.3462)
			(layers "B.Cu" "B.Mask" "B.Paste")
			(net "VR_FET_SW_P12V_STBY_PVDDQ_GHJ")
		)
		(pad "2" smd rect
			(at 0 1.27508 90)
			(size 2.6924 1.3462)
			(layers "B.Cu" "B.Mask" "B.Paste")
			(net "GND")
		)
	)
	(footprint ""
		(layer "B.Cu")
		(at 359.8164 -134.112)
		(property "Reference" "R3M3"
			(at 0 0 0)
			(layer "B.SilkS")
			(hide yes)
			(effects
				(font
					(size 1.27 1.27)
				)
				(justify mirror)
			)
		)
		(property "Value" ""
			(at 0 0 0)
			(layer "B.Fab")
			(effects
				(font
					(size 1.27 1.27)
				)
				(justify mirror)
			)
		)
		(duplicate_pad_numbers_are_jumpers no)
		(fp_rect
			(start 0.2794 0.9906)
			(end -0.2794 -0.1016)
			(stroke
				(width 0)
				(type default)
			)
			(fill no)
			(layer "B.CrtYd")
		)
		(fp_line
			(start -0.2794 -0.1016)
			(end 0.2794 -0.1016)
			(stroke
				(width 0.1)
				(type default)
			)
			(layer "B.Fab")
		)
		(fp_line
			(start -0.2794 0.9906)
			(end -0.2794 -0.1016)
			(stroke
				(width 0.1)
				(type default)
			)
			(layer "B.Fab")
		)
		(fp_line
			(start 0.2794 -0.1016)
			(end 0.2794 0.9906)
			(stroke
				(width 0.1)
				(type default)
			)
			(layer "B.Fab")
		)
		(fp_line
			(start 0.2794 0.9906)
			(end -0.2794 0.9906)
			(stroke
				(width 0.1)
				(type default)
			)
			(layer "B.Fab")
		)
		(pad "1" smd rect
			(at 0 0 180)
			(size 0.508 0.508)
			(layers "B.Cu" "B.Mask" "B.Paste")
			(net "PWRGD_PVDDQ_DEF_R")
		)
		(pad "2" smd rect
			(at 0 0.889 180)
			(size 0.508 0.508)
			(layers "B.Cu" "B.Mask" "B.Paste")
			(net "PWRGD_PVDDQ_DEF")
		)
		(zone
			(layer "B.Cu")
			(hatch none 0.5)
			(connect_pads
				(clearance 0)
			)
			(min_thickness 0.25)
			(keepout
				(tracks not_allowed)
				(vias allowed)
				(pads allowed)
				(copperpour not_allowed)
				(footprints allowed)
			)
			(placement
				(enabled no)
				(sheetname "")
			)
			(fill
				(thermal_gap 0.5)
				(thermal_bridge_width 0.5)
				(island_removal_mode 0)
			)
			(polygon
				(pts
					(xy 360.0704 -133.477) (xy 360.0704 -133.858) (xy 359.5624 -133.858) (xy 359.5624 -133.477)
				)
			)
		)
		(zone
			(layer "B.Cu")
			(hatch none 0.5)
			(connect_pads
				(clearance 0)
			)
			(min_thickness 0.25)
			(keepout
				(tracks allowed)
				(vias not_allowed)
				(pads allowed)
				(copperpour not_allowed)
				(footprints allowed)
			)
			(placement
				(enabled no)
				(sheetname "")
			)
			(fill
				(thermal_gap 0.5)
				(thermal_bridge_width 0.5)
				(island_removal_mode 0)
			)
			(polygon
				(pts
					(xy 360.0704 -133.477) (xy 360.0704 -133.858) (xy 359.5624 -133.858) (xy 359.5624 -133.477)
				)
			)
		)
	)
)
